(kicad_pcb
	(version 20241229)
	(generator "pcbnew")
	(generator_version "9.0")
	(general
		(thickness 1.711)
		(legacy_teardrops no)
	)
	(paper "A4")
	(title_block
		(title "Antmicro Baseboard for Jetson AGX Thor")
		(date "2026-02-18")
		(rev "1.1.0")
		(company "Antmicro Ltd")
		(comment 1 "www.antmicro.com")
		(comment 9 "footprints 11-13 of 1170")
	)
	(layers
		(0 "F.Cu" signal)
		(4 "In1.Cu" signal)
		(6 "In2.Cu" signal)
		(8 "In3.Cu" signal)
		(10 "In4.Cu" jumper)
		(12 "In5.Cu" signal)
		(14 "In6.Cu" signal)
		(16 "In7.Cu" signal)
		(18 "In8.Cu" signal)
		(2 "B.Cu" signal)
		(9 "F.Adhes" user "F.Adhesive")
		(11 "B.Adhes" user "B.Adhesive")
		(13 "F.Paste" user)
		(15 "B.Paste" user)
		(5 "F.SilkS" user "F.Silkscreen")
		(7 "B.SilkS" user "B.Silkscreen")
		(1 "F.Mask" user)
		(3 "B.Mask" user)
		(17 "Dwgs.User" user "User.Drawings")
		(19 "Cmts.User" user "User.Comments")
		(21 "Eco1.User" user "User.Eco1")
		(23 "Eco2.User" user "User.Eco2")
		(25 "Edge.Cuts" user)
		(27 "Margin" user)
		(31 "F.CrtYd" user "F.Courtyard")
		(29 "B.CrtYd" user "B.Courtyard")
		(35 "F.Fab" user)
		(33 "B.Fab" user)
	)
	(footprint "antmicro-footprints:SOT-523"
		(layer "F.Cu")
		(at 83.5 57.5 -90)
		(property "Reference" "Q18"
			(at -0.9 -1.4 270)
			(layer "F.SilkS")
			(effects
				(font
					(size 0.7 0.7)
					(thickness 0.15)
				)
				(justify right top)
			)
		)
		(property "Value" "DMG1012T-7"
			(at 0.1 1.824 90)
			(layer "F.Fab")
			(effects
				(font
					(size 0.7 0.7)
					(thickness 0.15)
				)
				(justify right top)
			)
		)
		(property "Datasheet" "https://www.diodes.com/assets/Datasheets/ds31783.pdf"
			(at 0 0 90)
			(layer "F.Fab")
			(hide yes)
			(effects
				(font
					(size 1.27 1.27)
					(thickness 0.15)
				)
			)
		)
		(property "Description" "Power MOSFET, N Channel, 20 V, 630 mA, 0.3 ohm, SOT-523, Surface Mount"
			(at 0 0 90)
			(layer "F.Fab")
			(hide yes)
			(effects
				(font
					(size 1.27 1.27)
					(thickness 0.15)
				)
			)
		)
		(property "MPN" "DMG1012T-7"
			(at 0 0 270)
			(unlocked yes)
			(layer "F.Fab")
			(hide yes)
			(effects
				(font
					(size 1 1)
					(thickness 0.15)
				)
			)
		)
		(property "Manufacturer" "Diodes Incorporated"
			(at 0 0 270)
			(unlocked yes)
			(layer "F.Fab")
			(hide yes)
			(effects
				(font
					(size 1 1)
					(thickness 0.15)
				)
			)
		)
		(property "Author" "Antmicro"
			(at 0 0 270)
			(unlocked yes)
			(layer "F.Fab")
			(hide yes)
			(effects
				(font
					(size 1 1)
					(thickness 0.15)
				)
			)
		)
		(property "License" "Apache-2.0"
			(at 0 0 270)
			(unlocked yes)
			(layer "F.Fab")
			(hide yes)
			(effects
				(font
					(size 1 1)
					(thickness 0.15)
				)
			)
		)
		(sheetname "/SoM_Power/")
		(sheetfile "som_power.kicad_sch")
		(attr smd)
		(fp_line
			(start -0.927 -0.051)
			(end -0.927 -0.351)
			(stroke
				(width 0.15)
				(type solid)
			)
			(layer "F.SilkS")
		)
		(fp_line
			(start -0.927 -0.351)
			(end -0.725 -0.551)
			(stroke
				(width 0.15)
				(type solid)
			)
			(layer "F.SilkS")
		)
		(fp_line
			(start -0.725 -0.551)
			(end -0.277 -0.551)
			(stroke
				(width 0.15)
				(type solid)
			)
			(layer "F.SilkS")
		)
		(fp_line
			(start -0.277 -0.551)
			(end -0.277 -0.75)
			(stroke
				(width 0.15)
				(type solid)
			)
			(layer "F.SilkS")
		)
		(fp_circle
			(center -0.9652 0.9652)
			(end -0.9152 0.9652)
			(stroke
				(width 0.15)
				(type solid)
			)
			(fill yes)
			(layer "F.SilkS")
		)
		(fp_line
			(start -1.12 1.15)
			(end 1.1 1.15)
			(stroke
				(width 0.05)
				(type solid)
			)
			(layer "F.CrtYd")
		)
		(fp_line
			(start -1.12 -1.16)
			(end -1.12 1.15)
			(stroke
				(width 0.05)
				(type solid)
			)
			(layer "F.CrtYd")
		)
		(fp_line
			(start -1.12 -1.16)
			(end 1.1 -1.16)
			(stroke
				(width 0.05)
				(type solid)
			)
			(layer "F.CrtYd")
		)
		(fp_line
			(start 1.1 -1.16)
			(end 1.1 1.15)
			(stroke
				(width 0.05)
				(type solid)
			)
			(layer "F.CrtYd")
		)
		(fp_line
			(start 0.8 0.424)
			(end -0.802 0.424)
			(stroke
				(width 0.15)
				(type solid)
			)
			(layer "F.Fab")
		)
		(fp_line
			(start -0.802 -0.276)
			(end -0.802 0.424)
			(stroke
				(width 0.15)
				(type solid)
			)
			(layer "F.Fab")
		)
		(fp_line
			(start -0.652 -0.425)
			(end -0.802 -0.276)
			(stroke
				(width 0.15)
				(type solid)
			)
			(layer "F.Fab")
		)
		(fp_line
			(start 0.8 -0.425)
			(end 0.8 0.424)
			(stroke
				(width 0.15)
				(type solid)
			)
			(layer "F.Fab")
		)
		(fp_line
			(start 0.8 -0.425)
			(end -0.652 -0.425)
			(stroke
				(width 0.15)
				(type solid)
			)
			(layer "F.Fab")
		)
		(fp_circle
			(center -0.9652 0.9652)
			(end -0.9144 0.9652)
			(stroke
				(width 0.15)
				(type solid)
			)
			(fill no)
			(layer "F.Fab")
		)
		(fp_text user "Author: Antmicro"
			(at -1.12 6.224 90)
			(layer "F.Fab")
			(effects
				(font
					(size 0.7 0.7)
					(thickness 0.15)
				)
				(justify right top)
			)
		)
		(fp_text user "License: Apache-2.0"
			(at -1.12 5.024 90)
			(layer "F.Fab")
			(effects
				(font
					(size 0.7 0.7)
					(thickness 0.15)
				)
				(justify right top)
			)
		)
		(fp_text user "${REFERENCE}"
			(at -1.12 3.824 90)
			(layer "F.Fab")
			(effects
				(font
					(size 0.7 0.7)
					(thickness 0.15)
				)
				(justify right top)
			)
		)
		(pad "1" smd rect
			(at -0.5 0.65 270)
			(size 0.4 0.51)
			(layers "F.Cu" "F.Mask" "F.Paste")
			(net 683 "/SoM_Power/~{SOM_PRSNT}")
			(pinfunction "G")
			(pintype "input")
		)
		(pad "2" smd rect
			(at 0.498 0.65 270)
			(size 0.4 0.51)
			(layers "F.Cu" "F.Mask" "F.Paste")
			(net 1 "GND")
			(pinfunction "S")
			(pintype "passive")
		)
		(pad "3" smd rect
			(at 0 -0.652 270)
			(size 0.4 0.51)
			(layers "F.Cu" "F.Mask" "F.Paste")
			(net 888 "Net-(Q18-D)")
			(pinfunction "D")
			(pintype "passive")
		)
	)
	(footprint "antmicro-footprints:C_0402_1005Metric"
		(layer "F.Cu")
		(at 170.784468 134.57)
		(descr "Capacitor SMD 0402")
		(tags "capacitor SMD 0402")
		(property "Reference" "C384"
			(at 1.015532 0.63 0)
			(layer "F.SilkS")
			(effects
				(font
					(size 0.7 0.7)
					(thickness 0.15)
				)
				(justify left bottom)
			)
		)
		(property "Value" "C_100n_0402"
			(at -1.022927 2.155213 0)
			(layer "F.Fab")
			(effects
				(font
					(size 0.7 0.7)
					(thickness 0.15)
				)
				(justify left bottom)
			)
		)
		(property "Datasheet" "https://www.murata.com/products/productdetail?partno=GRM155R61H104KE14%23"
			(at 0 0 0)
			(layer "F.Fab")
			(hide yes)
			(effects
				(font
					(size 1.27 1.27)
					(thickness 0.15)
				)
			)
		)
		(property "Description" "SMD Multilayer Ceramic Capacitor, 0.1 µF, 50 V, 0402 [1005 Metric], ± 10%, X5R, GRM Series"
			(at 0 0 0)
			(layer "F.Fab")
			(hide yes)
			(effects
				(font
					(size 1.27 1.27)
					(thickness 0.15)
				)
			)
		)
		(property "Manufacturer" "Murata"
			(at 0 0 0)
			(unlocked yes)
			(layer "F.Fab")
			(hide yes)
			(effects
				(font
					(size 1 1)
					(thickness 0.15)
				)
			)
		)
		(property "MPN" "GRM155R61H104KE14D"
			(at 0 0 0)
			(unlocked yes)
			(layer "F.Fab")
			(hide yes)
			(effects
				(font
					(size 1 1)
					(thickness 0.15)
				)
			)
		)
		(property "Val" "100n"
			(at 0 0 0)
			(unlocked yes)
			(layer "F.Fab")
			(hide yes)
			(effects
				(font
					(size 1 1)
					(thickness 0.15)
				)
			)
		)
		(property "License" "Apache-2.0"
			(at 0 0 0)
			(unlocked yes)
			(layer "F.Fab")
			(hide yes)
			(effects
				(font
					(size 1 1)
					(thickness 0.15)
				)
			)
		)
		(property "Author" "Antmicro"
			(at 0 0 0)
			(unlocked yes)
			(layer "F.Fab")
			(hide yes)
			(effects
				(font
					(size 1 1)
					(thickness 0.15)
				)
			)
		)
		(property "Voltage" "50V"
			(at 0 0 0)
			(unlocked yes)
			(layer "F.Fab")
			(hide yes)
			(effects
				(font
					(size 1 1)
					(thickness 0.15)
				)
			)
		)
		(property "Dielectric" "X5R"
			(at 0 0 0)
			(unlocked yes)
			(layer "F.Fab")
			(hide yes)
			(effects
				(font
					(size 1 1)
					(thickness 0.15)
				)
			)
		)
		(sheetname "/DCDC/")
		(sheetfile "dcdc.kicad_sch")
		(attr smd)
		(fp_rect
			(start -0.925 -0.47)
			(end 0.925 0.47)
			(stroke
				(width 0.05)
				(type default)
			)
			(fill no)
			(layer "F.CrtYd")
		)
		(fp_line
			(start -0.494 -0.25)
			(end 0.504 -0.25)
			(stroke
				(width 0.15)
				(type solid)
			)
			(layer "F.Fab")
		)
		(fp_line
			(start -0.494 0.248)
			(end -0.494 -0.25)
			(stroke
				(width 0.15)
				(type solid)
			)
			(layer "F.Fab")
		)
		(fp_line
			(start 0.504 -0.25)
			(end 0.504 0.248)
			(stroke
				(width 0.15)
				(type solid)
			)
			(layer "F.Fab")
		)
		(fp_line
			(start 0.504 0.248)
			(end -0.494 0.248)
			(stroke
				(width 0.15)
				(type solid)
			)
			(layer "F.Fab")
		)
		(fp_text user "Author: Antmicro"
			(at -0.939 3.399 0)
			(layer "F.Fab")
			(effects
				(font
					(size 0.7 0.7)
					(thickness 0.15)
				)
				(justify left bottom)
			)
		)
		(fp_text user "${REFERENCE}"
			(at -0.939 4.599 0)
			(layer "F.Fab")
			(effects
				(font
					(size 0.7 0.7)
					(thickness 0.15)
				)
				(justify left bottom)
			)
		)
		(fp_text user "License: Apache-2.0"
			(at -0.939 5.799 0)
			(layer "F.Fab")
			(effects
				(font
					(size 0.7 0.7)
					(thickness 0.15)
				)
				(justify left bottom)
			)
		)
		(pad "1" smd roundrect
			(at -0.48 0)
			(size 0.59 0.64)
			(layers "F.Cu" "F.Mask" "F.Paste")
			(roundrect_rratio 0.25)
			(net 1162 "Net-(U60-IN-)")
			(pintype "passive")
		)
		(pad "2" smd roundrect
			(at 0.48 0)
			(size 0.59 0.64)
			(layers "F.Cu" "F.Mask" "F.Paste")
			(roundrect_rratio 0.25)
			(net 1282 "Net-(U60-IN+)")
			(pintype "passive")
		)
	)
	(footprint "antmicro-footprints:C_0402_1005Metric"
		(layer "F.Cu")
		(at 218.8 112.7 180)
		(descr "Capacitor SMD 0402")
		(tags "capacitor SMD 0402")
		(property "Reference" "C102"
			(at 0.9 0.4 0)
			(layer "F.SilkS")
			(effects
				(font
					(size 0.7 0.7)
					(thickness 0.15)
				)
				(justify right top)
			)
		)
		(property "Value" "C_100n_0402"
			(at -1.022927 2.155213 0)
			(layer "F.Fab")
			(effects
				(font
					(size 0.7 0.7)
					(thickness 0.15)
				)
				(justify right top)
			)
		)
		(property "Datasheet" "https://www.murata.com/products/productdetail?partno=GRM155R61H104KE14%23"
			(at 0 0 0)
			(layer "F.Fab")
			(hide yes)
			(effects
				(font
					(size 1.27 1.27)
					(thickness 0.15)
				)
			)
		)
		(property "Description" "SMD Multilayer Ceramic Capacitor, 0.1 µF, 50 V, 0402 [1005 Metric], ± 10%, X5R, GRM Series"
			(at 0 0 0)
			(layer "F.Fab")
			(hide yes)
			(effects
				(font
					(size 1.27 1.27)
					(thickness 0.15)
				)
			)
		)
		(property "Manufacturer" "Murata"
			(at 0 0 180)
			(unlocked yes)
			(layer "F.Fab")
			(hide yes)
			(effects
				(font
					(size 1 1)
					(thickness 0.15)
				)
			)
		)
		(property "MPN" "GRM155R61H104KE14D"
			(at 0 0 180)
			(unlocked yes)
			(layer "F.Fab")
			(hide yes)
			(effects
				(font
					(size 1 1)
					(thickness 0.15)
				)
			)
		)
		(property "Val" "100n"
			(at 0 0 180)
			(unlocked yes)
			(layer "F.Fab")
			(hide yes)
			(effects
				(font
					(size 1 1)
					(thickness 0.15)
				)
			)
		)
		(property "License" "Apache-2.0"
			(at 0 0 180)
			(unlocked yes)
			(layer "F.Fab")
			(hide yes)
			(effects
				(font
					(size 1 1)
					(thickness 0.15)
				)
			)
		)
		(property "Author" "Antmicro"
			(at 0 0 180)
			(unlocked yes)
			(layer "F.Fab")
			(hide yes)
			(effects
				(font
					(size 1 1)
					(thickness 0.15)
				)
			)
		)
		(property "Voltage" "50V"
			(at 0 0 180)
			(unlocked yes)
			(layer "F.Fab")
			(hide yes)
			(effects
				(font
					(size 1 1)
					(thickness 0.15)
				)
			)
		)
		(property "Dielectric" "X5R"
			(at 0 0 180)
			(unlocked yes)
			(layer "F.Fab")
			(hide yes)
			(effects
				(font
					(size 1 1)
					(thickness 0.15)
				)
			)
		)
		(sheetname "/USB Hub/")
		(sheetfile "usb_hub.kicad_sch")
		(attr smd)
		(fp_rect
			(start -0.925 -0.47)
			(end 0.925 0.47)
			(stroke
				(width 0.05)
				(type default)
			)
			(fill no)
			(layer "F.CrtYd")
		)
		(fp_line
			(start 0.504 0.248)
			(end -0.494 0.248)
			(stroke
				(width 0.15)
				(type solid)
			)
			(layer "F.Fab")
		)
		(fp_line
			(start 0.504 -0.25)
			(end 0.504 0.248)
			(stroke
				(width 0.15)
				(type solid)
			)
			(layer "F.Fab")
		)
		(fp_line
			(start -0.494 0.248)
			(end -0.494 -0.25)
			(stroke
				(width 0.15)
				(type solid)
			)
			(layer "F.Fab")
		)
		(fp_line
			(start -0.494 -0.25)
			(end 0.504 -0.25)
			(stroke
				(width 0.15)
				(type solid)
			)
			(layer "F.Fab")
		)
		(fp_text user "License: Apache-2.0"
			(at -0.939 5.799 0)
			(layer "F.Fab")
			(effects
				(font
					(size 0.7 0.7)
					(thickness 0.15)
				)
				(justify right top)
			)
		)
		(fp_text user "${REFERENCE}"
			(at -0.939 4.599 0)
			(layer "F.Fab")
			(effects
				(font
					(size 0.7 0.7)
					(thickness 0.15)
				)
				(justify right top)
			)
		)
		(fp_text user "Author: Antmicro"
			(at -0.939 3.399 0)
			(layer "F.Fab")
			(effects
				(font
					(size 0.7 0.7)
					(thickness 0.15)
				)
				(justify right top)
			)
		)
		(pad "1" smd roundrect
			(at -0.48 0 180)
			(size 0.59 0.64)
			(layers "F.Cu" "F.Mask" "F.Paste")
			(roundrect_rratio 0.25)
			(net 103 "/USB Hub/USBC3_CONN_TX2_N")
			(pintype "passive")
		)
		(pad "2" smd roundrect
			(at 0.48 0 180)
			(size 0.59 0.64)
			(layers "F.Cu" "F.Mask" "F.Paste")
			(roundrect_rratio 0.25)
			(net 212 "/USB Hub/USBC3_TX_{2}+")
			(pintype "passive")
		)
	)
)
